# T6G (Grand Teton) — schematic netlist excerpt (pin names and nets, part order shuffled) for the footprints in the layout excerpt that follows; sources: Cadence DE-HDL packaged netlist, KiCad conversion of 04192023_DAF0TMB3IC0_F0TG_MB_C_brd_V02_OCP.brd

J90  SCONN56_123276793  SCONN56_1-2327679-3 IO  pkg CON_F56S2H4D_P0-6W4-6_LUHXA  page 145
  GND_A1  = GND
  GND_A2  = GND
  GND_A3  = GND
  GND_A4  = GND
  GND_A5  = GND
  GND_A6  = GND
  SMBCLK  = SMB_E1S_3V3AUX_ISO_SCL
  SMBDAT  = SMB_E1S_3V3AUX_ISO_SDA
  \smbrst#\  = RST_SMB_E1S_0_N
  \led#_activity\  = FM_LED_ACTIVE_E1S_0_BUF
  \perst1#_clkreq#\  = E1S_0_PERST1_CLKREQ_N
  \prsnt0#\  = E1S_0_PRSNT_N
  GND_A13  = GND
  REFCLK_N1  = TP_CLK_100M_E1S_0_DN
  REFCLK_P1  = TP_CLK_100M_E1S_0_DP
  GND_A16  = GND
  PER_N0  = P3E_CPU0_P4_RX_DP<0>
  PER_P0  = P3E_CPU0_P4_RX_DN<0>
  GND_A19  = GND
  PER_N1  = P3E_CPU0_P4_RX_DP<1>
  PER_P1  = P3E_CPU0_P4_RX_DN<1>
  GND_A22  = GND
  PER_N2  = P3E_CPU0_P4_RX_DP<2>
  PER_P2  = P3E_CPU0_P4_RX_DN<2>
  GND_A25  = GND
  PER_N3  = P3E_CPU0_P4_RX_DP<3>
  PER_P3  = P3E_CPU0_P4_RX_DN<3>
  GND_A28  = GND
  P12V_B1  = P12V_E1S_0_R
  P12V_B2  = P12V_E1S_0_R
  P12V_B3  = P12V_E1S_0_R
  P12V_B4  = P12V_E1S_0_R
  P12V_B5  = P12V_E1S_0_R
  P12V_B6  = P12V_E1S_0_R
  MFG  = TP_E1S_0_MFG
  RFU  = TP_E1S_0_RFU
  \dualporten#\  = PU_E1S_0_DUALPORT_EN_N
  \perst0#\  = RST_PCIE_E1S_PERST_N
  P3V3_AUX  = P3V3_E1S_0
  PWRDIS  = E1S_0_PWRDIS
  GND_B13  = GND
  REFCLK_N0  = CLK_100M_CPU0_CLK12_DN
  REFCLK_P0  = CLK_100M_CPU0_CLK12_DP
  GND_B16  = GND
  PET_N0  = P3E_CPU0_P4_TX_C_DP<0>
  PET_P0  = P3E_CPU0_P4_TX_C_DN<0>
  GND_B19  = GND
  PET_N1  = P3E_CPU0_P4_TX_C_DP<1>
  PET_P1  = P3E_CPU0_P4_TX_C_DN<1>
  GND_B22  = GND
  PET_N2  = P3E_CPU0_P4_TX_C_DP<2>
  PET_P2  = P3E_CPU0_P4_TX_C_DN<2>
  GND_B25  = GND
  PET_N3  = P3E_CPU0_P4_TX_C_DN<3>
  PET_P3  = P3E_CPU0_P4_TX_C_DP<3>
  GND_B28  = GND
  G1  = GND
  G2  = GND

(kicad_pcb
	(version 20260206)
	(generator "pcbnew")
	(generator_version "10.0")
	(general
		(thickness 1.6)
		(legacy_teardrops no)
	)
	(paper "A4")
	(title_block
		(title "04192023_DAF0TMB3IC0_F0TG_MB_C_brd_V02_OCP.brd")
		(comment 1 "Grand Teton / footprint 3138 of 8354 (J90), pads 47-60 of 60")
	)
	(layers
		(0 "F.Cu" signal "TOP")
		(4 "In1.Cu" signal "GND")
		(6 "In2.Cu" signal "IN1")
		(8 "In3.Cu" signal "GND1")
		(10 "In4.Cu" signal "IN2")
		(12 "In5.Cu" signal "GND2")
		(14 "In6.Cu" signal "IN3")
		(16 "In7.Cu" signal "GND3")
		(18 "In8.Cu" signal "VCC")
		(20 "In9.Cu" signal "VCC1")
		(22 "In10.Cu" signal "GND4")
		(24 "In11.Cu" signal "IN4")
		(26 "In12.Cu" signal "GND5")
		(28 "In13.Cu" signal "IN5")
		(30 "In14.Cu" signal "GND6")
		(32 "In15.Cu" signal "IN6")
		(34 "In16.Cu" signal "GND7")
		(2 "B.Cu" signal "BOTTOM")
		(9 "F.Adhes" user "F.Adhesive")
		(11 "B.Adhes" user "B.Adhesive")
		(13 "F.Paste" user "Package Geometry/Pastemask Top")
		(15 "B.Paste" user "Package Geometry/Pastemask Bottom")
		(5 "F.SilkS" user "Ref Des/Silkscreen Top")
		(7 "B.SilkS" user "Ref Des/Silkscreen Bottom")
		(1 "F.Mask" user "Board Geometry/Soldermask Top")
		(3 "B.Mask" user "Board Geometry/Soldermask Bottom")
		(17 "Dwgs.User" user "User.Drawings")
		(19 "Cmts.User" user "User.Comments")
		(21 "Eco1.User" user "User.Eco1")
		(23 "Eco2.User" user "User.Eco2")
		(25 "Edge.Cuts" user "Board Geometry/Outline")
		(27 "Margin" user)
		(31 "F.CrtYd" user "Package Geometry/Place Bound Top")
		(29 "B.CrtYd" user "Package Geometry/Place Bound Bottom")
		(35 "F.Fab" user "Ref Des/Assembly Top")
		(33 "B.Fab" user "Ref Des/Assembly Bottom")
	)
	(footprint ""
		(layer "F.Cu")
		(at 234.300014 -50.55997 180)
		(property "Reference" "J90"
			(at 4.181094 -11.365484 90)
			(unlocked yes)
			(layer "F.SilkS")
			(effects
				(font
					(size 0.7874 0.5842)
					(thickness 0.1524)
				)
			)
		)
		(property "Value" ""
			(at 0 0 180)
			(layer "F.Fab")
			(effects
				(font
					(size 1.27 1.27)
				)
			)
		)
		(duplicate_pad_numbers_are_jumpers no)
		(pad "B17" smd rect
			(at -2.29997 1.605026 90)
			(size 0.381 1.27)
			(layers "F.Cu" "F.Mask" "F.Paste")
			(net "P3E_CPU0_P4_TX_C_DP<0>")
		)
		(pad "B18" smd rect
			(at -2.29997 2.204974 90)
			(size 0.381 1.27)
			(layers "F.Cu" "F.Mask" "F.Paste")
			(net "P3E_CPU0_P4_TX_C_DN<0>")
		)
		(pad "B19" smd rect
			(at -2.29997 2.804922 90)
			(size 0.381 1.27)
			(layers "F.Cu" "F.Mask" "F.Paste")
			(net "GND")
		)
		(pad "B20" smd rect
			(at -2.29997 3.405124 90)
			(size 0.381 1.27)
			(layers "F.Cu" "F.Mask" "F.Paste")
			(net "P3E_CPU0_P4_TX_C_DP<1>")
		)
		(pad "B21" smd rect
			(at -2.29997 4.005072 90)
			(size 0.381 1.27)
			(layers "F.Cu" "F.Mask" "F.Paste")
			(net "P3E_CPU0_P4_TX_C_DN<1>")
		)
		(pad "B22" smd rect
			(at -2.29997 4.60502 90)
			(size 0.381 1.27)
			(layers "F.Cu" "F.Mask" "F.Paste")
			(net "GND")
		)
		(pad "B23" smd rect
			(at -2.29997 5.204968 90)
			(size 0.381 1.27)
			(layers "F.Cu" "F.Mask" "F.Paste")
			(net "P3E_CPU0_P4_TX_C_DP<2>")
		)
		(pad "B24" smd rect
			(at -2.29997 5.804916 90)
			(size 0.381 1.27)
			(layers "F.Cu" "F.Mask" "F.Paste")
			(net "P3E_CPU0_P4_TX_C_DN<2>")
		)
		(pad "B25" smd rect
			(at -2.29997 6.405118 90)
			(size 0.381 1.27)
			(layers "F.Cu" "F.Mask" "F.Paste")
			(net "GND")
		)
		(pad "B26" smd rect
			(at -2.29997 7.005066 90)
			(size 0.381 1.27)
			(layers "F.Cu" "F.Mask" "F.Paste")
			(net "P3E_CPU0_P4_TX_C_DN<3>")
		)
		(pad "B27" smd rect
			(at -2.29997 7.605014 90)
			(size 0.381 1.27)
			(layers "F.Cu" "F.Mask" "F.Paste")
			(net "P3E_CPU0_P4_TX_C_DP<3>")
		)
		(pad "B28" smd rect
			(at -2.29997 8.204962 90)
			(size 0.381 1.27)
			(layers "F.Cu" "F.Mask" "F.Paste")
			(net "GND")
		)
		(pad "G1" thru_hole oval
			(at 0 -11.364976 90)
			(size 1.6256 3.4798)
			(drill oval 1.1176 2.4638)
			(layers "*.Cu" "*.Mask")
			(remove_unused_layers no)
			(net "GND")
			(clearance 0.127)
			(thermal_gap 0.127)
		)
		(pad "G2" thru_hole oval
			(at 0 11.364976 90)
			(size 1.6256 3.4798)
			(drill oval 1.1176 2.4638)
			(layers "*.Cu" "*.Mask")
			(remove_unused_layers no)
			(net "GND")
			(clearance 0.127)
			(thermal_gap 0.127)
		)
	)
)
